(kicad_pcb
	(version 20260206)
	(generator "pcbnew")
	(generator_version "10.0")
	(general
		(thickness 1.6)
		(legacy_teardrops no)
	)
	(paper "A4")
	(title_block
		(title "Bryce Canyon_IOM_M2_16342-2_OCP.brd")
		(comment 1 "Bryce Canyon / footprints 955-961 of 1146")
	)
	(layers
		(0 "F.Cu" signal "TOP")
		(4 "In1.Cu" signal "L2GND")
		(6 "In2.Cu" signal "L3")
		(8 "In3.Cu" signal "L4VCC")
		(10 "In4.Cu" signal "L5VCC")
		(12 "In5.Cu" signal "L6")
		(14 "In6.Cu" signal "L7GND")
		(2 "B.Cu" signal "BOTTOM")
		(9 "F.Adhes" user "F.Adhesive")
		(11 "B.Adhes" user "B.Adhesive")
		(13 "F.Paste" user "Package Geometry/Pastemask Top")
		(15 "B.Paste" user "Package Geometry/Pastemask Bottom")
		(5 "F.SilkS" user "Ref Des/Silkscreen Top")
		(7 "B.SilkS" user "Ref Des/Silkscreen Bottom")
		(1 "F.Mask" user "Board Geometry/Soldermask Top")
		(3 "B.Mask" user "Board Geometry/Soldermask Bottom")
		(17 "Dwgs.User" user "User.Drawings")
		(19 "Cmts.User" user "User.Comments")
		(21 "Eco1.User" user "User.Eco1")
		(23 "Eco2.User" user "User.Eco2")
		(25 "Edge.Cuts" user "Board Geometry/Outline")
		(27 "Margin" user)
		(31 "F.CrtYd" user "Package Geometry/Place Bound Top")
		(29 "B.CrtYd" user "Package Geometry/Place Bound Bottom")
		(35 "F.Fab" user "Ref Des/Assembly Top")
		(33 "B.Fab" user "Ref Des/Assembly Bottom")
	)
	(footprint ""
		(layer "B.Cu")
		(at 83.7692 -98.494596 -90)
		(property "Reference" "R64"
			(at 0 0 90)
			(layer "B.SilkS")
			(hide yes)
			(effects
				(font
					(size 1.27 1.27)
				)
				(justify mirror)
			)
		)
		(property "Value" "10KR2F-2-GP"
			(at -0.064008 -3.993896 270)
			(unlocked yes)
			(layer "B.Fab")
			(hide yes)
			(effects
				(font
					(size 1.016 1.016)
					(thickness 0.1524)
				)
				(justify mirror)
			)
		)
		(property "Device Type" "R402H16"
			(at -0.064008 -5.517896 270)
			(unlocked yes)
			(layer "B.Fab")
			(hide yes)
			(effects
				(font
					(size 1.016 1.016)
					(thickness 0.1524)
				)
				(justify mirror)
			)
		)
		(duplicate_pad_numbers_are_jumpers no)
		(fp_line
			(start -0.508 -0.9398)
			(end 0.508 -0.9398)
			(stroke
				(width 0.1524)
				(type default)
			)
			(layer "B.SilkS")
		)
		(fp_line
			(start 0.508 -0.9398)
			(end 0.508 0.9398)
			(stroke
				(width 0.1524)
				(type default)
			)
			(layer "B.SilkS")
		)
		(fp_rect
			(start 0.508 0.9398)
			(end -0.508 -0.9398)
			(stroke
				(width 0)
				(type default)
			)
			(fill no)
			(layer "B.CrtYd")
		)
		(fp_rect
			(start 0.508 0.9398)
			(end -0.508 -0.9398)
			(stroke
				(width 0)
				(type default)
			)
			(fill no)
			(layer "B.Fab")
		)
		(pad "1" smd custom
			(at 0 -0.4445 90)
			(size 0.1397 0.1397)
			(layers "B.Cu" "B.Mask" "B.Paste")
			(net "P3V3_STBY")
			(options
				(clearance outline)
				(anchor circle)
			)
			(primitives
				(gr_poly
					(pts
						(arc
							(start -0.1778 0.2794)
							(mid -0.249642 0.249642)
							(end -0.2794 0.1778)
						)
						(arc
							(start -0.2794 -0.1778)
							(mid -0.249642 -0.249642)
							(end -0.1778 -0.2794)
						)
						(arc
							(start 0.1778 -0.2794)
							(mid 0.249642 -0.249642)
							(end 0.2794 -0.1778)
						)
						(arc
							(start 0.2794 0.1778)
							(mid 0.249642 0.249642)
							(end 0.1778 0.2794)
						)
					)
					(width 0)
					(fill yes)
				)
			)
		)
		(pad "2" smd custom
			(at 0 0.4445 90)
			(size 0.1397 0.1397)
			(layers "B.Cu" "B.Mask" "B.Paste")
			(net "MEZZ_A_PRSNT_120_N")
			(options
				(clearance outline)
				(anchor circle)
			)
			(primitives
				(gr_poly
					(pts
						(arc
							(start -0.1778 0.2794)
							(mid -0.249642 0.249642)
							(end -0.2794 0.1778)
						)
						(arc
							(start -0.2794 -0.1778)
							(mid -0.249642 -0.249642)
							(end -0.1778 -0.2794)
						)
						(arc
							(start 0.1778 -0.2794)
							(mid 0.249642 -0.249642)
							(end 0.2794 -0.1778)
						)
						(arc
							(start 0.2794 0.1778)
							(mid 0.249642 0.249642)
							(end 0.1778 0.2794)
						)
					)
					(width 0)
					(fill yes)
				)
			)
		)
	)
	(footprint ""
		(layer "B.Cu")
		(at 82.87639 -143.814292 -90)
		(property "Reference" "R127"
			(at 0 0 90)
			(layer "B.SilkS")
			(hide yes)
			(effects
				(font
					(size 1.27 1.27)
				)
				(justify mirror)
			)
		)
		(property "Value" "0R2J-2-GP"
			(at -0.064008 -3.993896 270)
			(unlocked yes)
			(layer "B.Fab")
			(hide yes)
			(effects
				(font
					(size 1.016 1.016)
					(thickness 0.1524)
				)
				(justify mirror)
			)
		)
		(property "Device Type" "R402H16"
			(at -0.064008 -5.517896 270)
			(unlocked yes)
			(layer "B.Fab")
			(hide yes)
			(effects
				(font
					(size 1.016 1.016)
					(thickness 0.1524)
				)
				(justify mirror)
			)
		)
		(duplicate_pad_numbers_are_jumpers no)
		(fp_line
			(start -0.508 -0.9398)
			(end 0.508 -0.9398)
			(stroke
				(width 0.1524)
				(type default)
			)
			(layer "B.SilkS")
		)
		(fp_line
			(start 0.508 -0.9398)
			(end 0.508 0.9398)
			(stroke
				(width 0.1524)
				(type default)
			)
			(layer "B.SilkS")
		)
		(fp_rect
			(start 0.508 0.9398)
			(end -0.508 -0.9398)
			(stroke
				(width 0)
				(type default)
			)
			(fill no)
			(layer "B.CrtYd")
		)
		(fp_rect
			(start 0.508 0.9398)
			(end -0.508 -0.9398)
			(stroke
				(width 0)
				(type default)
			)
			(fill no)
			(layer "B.Fab")
		)
		(pad "1" smd custom
			(at 0 -0.4445 90)
			(size 0.1397 0.1397)
			(layers "B.Cu" "B.Mask" "B.Paste")
			(net "I2C_EXP_LOC_SCL")
			(options
				(clearance outline)
				(anchor circle)
			)
			(primitives
				(gr_poly
					(pts
						(arc
							(start -0.1778 0.2794)
							(mid -0.249642 0.249642)
							(end -0.2794 0.1778)
						)
						(arc
							(start -0.2794 -0.1778)
							(mid -0.249642 -0.249642)
							(end -0.1778 -0.2794)
						)
						(arc
							(start 0.1778 -0.2794)
							(mid 0.249642 -0.249642)
							(end 0.2794 -0.1778)
						)
						(arc
							(start 0.2794 0.1778)
							(mid 0.249642 0.249642)
							(end 0.1778 0.2794)
						)
					)
					(width 0)
					(fill yes)
				)
			)
		)
		(pad "2" smd custom
			(at 0 0.4445 90)
			(size 0.1397 0.1397)
			(layers "B.Cu" "B.Mask" "B.Paste")
			(net "I2C_EXP_LOC_SCL_R")
			(options
				(clearance outline)
				(anchor circle)
			)
			(primitives
				(gr_poly
					(pts
						(arc
							(start -0.1778 0.2794)
							(mid -0.249642 0.249642)
							(end -0.2794 0.1778)
						)
						(arc
							(start -0.2794 -0.1778)
							(mid -0.249642 -0.249642)
							(end -0.1778 -0.2794)
						)
						(arc
							(start 0.1778 -0.2794)
							(mid 0.249642 -0.249642)
							(end 0.2794 -0.1778)
						)
						(arc
							(start 0.2794 0.1778)
							(mid 0.249642 0.249642)
							(end 0.1778 0.2794)
						)
					)
					(width 0)
					(fill yes)
				)
			)
		)
	)
	(footprint ""
		(layer "B.Cu")
		(at 33.9344 -152.0952 180)
		(property "Reference" "C93"
			(at 0 0 0)
			(layer "B.SilkS")
			(hide yes)
			(effects
				(font
					(size 1.27 1.27)
				)
				(justify mirror)
			)
		)
		(property "Value" "SCD1U16V2KX-3GP"
			(at -1.1811 -2.7051 180)
			(unlocked yes)
			(layer "B.Fab")
			(hide yes)
			(effects
				(font
					(size 1.016 1.016)
					(thickness 0.1524)
				)
				(justify mirror)
			)
		)
		(property "Device Type" "C402H22"
			(at -1.1811 -4.2291 180)
			(unlocked yes)
			(layer "B.Fab")
			(hide yes)
			(effects
				(font
					(size 1.016 1.016)
					(thickness 0.1524)
				)
				(justify mirror)
			)
		)
		(duplicate_pad_numbers_are_jumpers no)
		(fp_rect
			(start 0.4318 0.9525)
			(end -0.4318 -0.9525)
			(stroke
				(width 0)
				(type default)
			)
			(fill no)
			(layer "B.CrtYd")
		)
		(fp_rect
			(start 0.4318 0.9525)
			(end -0.4318 -0.9525)
			(stroke
				(width 0)
				(type default)
			)
			(fill no)
			(layer "B.Fab")
		)
		(pad "1" smd custom
			(at 0 -0.4445)
			(size 0.1524 0.1524)
			(layers "B.Cu" "B.Mask" "B.Paste")
			(net "MPLLAV33")
			(options
				(clearance outline)
				(anchor circle)
			)
			(primitives
				(gr_poly
					(pts
						(arc
							(start 0.3048 0.2032)
							(mid 0.275042 0.275042)
							(end 0.2032 0.3048)
						)
						(arc
							(start -0.2032 0.3048)
							(mid -0.275042 0.275042)
							(end -0.3048 0.2032)
						)
						(arc
							(start -0.3048 -0.2032)
							(mid -0.275042 -0.275042)
							(end -0.2032 -0.3048)
						)
						(arc
							(start 0.2032 -0.3048)
							(mid 0.275042 -0.275042)
							(end 0.3048 -0.2032)
						)
					)
					(width 0)
					(fill yes)
				)
			)
		)
		(pad "2" smd custom
			(at 0 0.4445)
			(size 0.1524 0.1524)
			(layers "B.Cu" "B.Mask" "B.Paste")
			(net "GND")
			(options
				(clearance outline)
				(anchor circle)
			)
			(primitives
				(gr_poly
					(pts
						(arc
							(start 0.3048 0.2032)
							(mid 0.275042 0.275042)
							(end 0.2032 0.3048)
						)
						(arc
							(start -0.2032 0.3048)
							(mid -0.275042 0.275042)
							(end -0.3048 0.2032)
						)
						(arc
							(start -0.3048 -0.2032)
							(mid -0.275042 -0.275042)
							(end -0.2032 -0.3048)
						)
						(arc
							(start 0.2032 -0.3048)
							(mid 0.275042 -0.275042)
							(end 0.3048 -0.2032)
						)
					)
					(width 0)
					(fill yes)
				)
			)
		)
	)
	(footprint ""
		(layer "B.Cu")
		(at 67.818 -149.479 90)
		(property "Reference" "R386"
			(at 0 0 90)
			(layer "B.SilkS")
			(hide yes)
			(effects
				(font
					(size 1.27 1.27)
				)
				(justify mirror)
			)
		)
		(property "Value" "4K7R2F-GP"
			(at -0.064008 -3.993896 90)
			(unlocked yes)
			(layer "B.Fab")
			(hide yes)
			(effects
				(font
					(size 1.016 1.016)
					(thickness 0.1524)
				)
				(justify mirror)
			)
		)
		(property "Device Type" "R402H16"
			(at -0.064008 -5.517896 90)
			(unlocked yes)
			(layer "B.Fab")
			(hide yes)
			(effects
				(font
					(size 1.016 1.016)
					(thickness 0.1524)
				)
				(justify mirror)
			)
		)
		(duplicate_pad_numbers_are_jumpers no)
		(fp_line
			(start 0.508 -0.9398)
			(end 0.508 0.9398)
			(stroke
				(width 0.1524)
				(type default)
			)
			(layer "B.SilkS")
		)
		(fp_line
			(start -0.508 -0.9398)
			(end 0.508 -0.9398)
			(stroke
				(width 0.1524)
				(type default)
			)
			(layer "B.SilkS")
		)
		(fp_rect
			(start 0.508 0.9398)
			(end -0.508 -0.9398)
			(stroke
				(width 0)
				(type default)
			)
			(fill no)
			(layer "B.CrtYd")
		)
		(fp_rect
			(start 0.508 0.9398)
			(end -0.508 -0.9398)
			(stroke
				(width 0)
				(type default)
			)
			(fill no)
			(layer "B.Fab")
		)
		(pad "1" smd custom
			(at 0 -0.4445 270)
			(size 0.1397 0.1397)
			(layers "B.Cu" "B.Mask" "B.Paste")
			(net "GND")
			(options
				(clearance outline)
				(anchor circle)
			)
			(primitives
				(gr_poly
					(pts
						(arc
							(start -0.1778 0.2794)
							(mid -0.249642 0.249642)
							(end -0.2794 0.1778)
						)
						(arc
							(start -0.2794 -0.1778)
							(mid -0.249642 -0.249642)
							(end -0.1778 -0.2794)
						)
						(arc
							(start 0.1778 -0.2794)
							(mid 0.249642 -0.249642)
							(end 0.2794 -0.1778)
						)
						(arc
							(start 0.2794 0.1778)
							(mid 0.249642 0.249642)
							(end 0.1778 0.2794)
						)
					)
					(width 0)
					(fill yes)
				)
			)
		)
		(pad "2" smd custom
			(at 0 0.4445 270)
			(size 0.1397 0.1397)
			(layers "B.Cu" "B.Mask" "B.Paste")
			(net "NCSI_TXD0")
			(options
				(clearance outline)
				(anchor circle)
			)
			(primitives
				(gr_poly
					(pts
						(arc
							(start -0.1778 0.2794)
							(mid -0.249642 0.249642)
							(end -0.2794 0.1778)
						)
						(arc
							(start -0.2794 -0.1778)
							(mid -0.249642 -0.249642)
							(end -0.1778 -0.2794)
						)
						(arc
							(start 0.1778 -0.2794)
							(mid 0.249642 -0.249642)
							(end 0.2794 -0.1778)
						)
						(arc
							(start 0.2794 0.1778)
							(mid 0.249642 0.249642)
							(end 0.1778 0.2794)
						)
					)
					(width 0)
					(fill yes)
				)
			)
		)
	)
	(footprint ""
		(layer "B.Cu")
		(at 57.0738 -150.6728 -90)
		(property "Reference" "R388"
			(at 0 0 90)
			(layer "B.SilkS")
			(hide yes)
			(effects
				(font
					(size 1.27 1.27)
				)
				(justify mirror)
			)
		)
		(property "Value" "4K7R2F-GP"
			(at -0.064008 -3.993896 270)
			(unlocked yes)
			(layer "B.Fab")
			(hide yes)
			(effects
				(font
					(size 1.016 1.016)
					(thickness 0.1524)
				)
				(justify mirror)
			)
		)
		(property "Device Type" "R402H16"
			(at -0.064008 -5.517896 270)
			(unlocked yes)
			(layer "B.Fab")
			(hide yes)
			(effects
				(font
					(size 1.016 1.016)
					(thickness 0.1524)
				)
				(justify mirror)
			)
		)
		(duplicate_pad_numbers_are_jumpers no)
		(fp_line
			(start -0.508 -0.9398)
			(end 0.508 -0.9398)
			(stroke
				(width 0.1524)
				(type default)
			)
			(layer "B.SilkS")
		)
		(fp_line
			(start 0.508 -0.9398)
			(end 0.508 0.9398)
			(stroke
				(width 0.1524)
				(type default)
			)
			(layer "B.SilkS")
		)
		(fp_rect
			(start 0.508 0.9398)
			(end -0.508 -0.9398)
			(stroke
				(width 0)
				(type default)
			)
			(fill no)
			(layer "B.CrtYd")
		)
		(fp_rect
			(start 0.508 0.9398)
			(end -0.508 -0.9398)
			(stroke
				(width 0)
				(type default)
			)
			(fill no)
			(layer "B.Fab")
		)
		(pad "1" smd custom
			(at 0 -0.4445 90)
			(size 0.1397 0.1397)
			(layers "B.Cu" "B.Mask" "B.Paste")
			(net "GND")
			(options
				(clearance outline)
				(anchor circle)
			)
			(primitives
				(gr_poly
					(pts
						(arc
							(start -0.1778 0.2794)
							(mid -0.249642 0.249642)
							(end -0.2794 0.1778)
						)
						(arc
							(start -0.2794 -0.1778)
							(mid -0.249642 -0.249642)
							(end -0.1778 -0.2794)
						)
						(arc
							(start 0.1778 -0.2794)
							(mid 0.249642 -0.249642)
							(end 0.2794 -0.1778)
						)
						(arc
							(start 0.2794 0.1778)
							(mid 0.249642 0.249642)
							(end 0.1778 0.2794)
						)
					)
					(width 0)
					(fill yes)
				)
			)
		)
		(pad "2" smd custom
			(at 0 0.4445 90)
			(size 0.1397 0.1397)
			(layers "B.Cu" "B.Mask" "B.Paste")
			(net "MAC1_TXD2")
			(options
				(clearance outline)
				(anchor circle)
			)
			(primitives
				(gr_poly
					(pts
						(arc
							(start -0.1778 0.2794)
							(mid -0.249642 0.249642)
							(end -0.2794 0.1778)
						)
						(arc
							(start -0.2794 -0.1778)
							(mid -0.249642 -0.249642)
							(end -0.1778 -0.2794)
						)
						(arc
							(start 0.1778 -0.2794)
							(mid 0.249642 -0.249642)
							(end 0.2794 -0.1778)
						)
						(arc
							(start 0.2794 0.1778)
							(mid 0.249642 0.249642)
							(end 0.1778 0.2794)
						)
					)
					(width 0)
					(fill yes)
				)
			)
		)
	)
	(footprint ""
		(layer "B.Cu")
		(at 42.931334 -154.997912 -90)
		(property "Reference" "TP66"
			(at 0 0 90)
			(layer "B.SilkS")
			(hide yes)
			(effects
				(font
					(size 1.27 1.27)
				)
				(justify mirror)
			)
		)
		(property "Value" "TPAD28-2-GP"
			(at 0.0127 -1.6637 270)
			(unlocked yes)
			(layer "B.Fab")
			(hide yes)
			(effects
				(font
					(size 1.016 1.016)
					(thickness 0.1524)
				)
				(justify mirror)
			)
		)
		(property "Device Type" "TPAD28"
			(at 0.0127 -3.1877 270)
			(unlocked yes)
			(layer "B.Fab")
			(hide yes)
			(effects
				(font
					(size 1.016 1.016)
					(thickness 0.1524)
				)
				(justify mirror)
			)
		)
		(duplicate_pad_numbers_are_jumpers no)
		(fp_poly
			(pts
				(arc
					(start 0 -0.3556)
					(mid 0 0.3556)
					(end 0 -0.3556)
				)
			)
			(stroke
				(width 0)
				(type default)
			)
			(fill no)
			(layer "B.CrtYd")
		)
		(fp_poly
			(pts
				(arc
					(start 0 -0.6096)
					(mid 0 0.6096)
					(end 0 -0.6096)
				)
			)
			(stroke
				(width 0)
				(type default)
			)
			(fill no)
			(layer "B.Fab")
		)
		(pad "1" smd circle
			(at 0 0 90)
			(size 0.7112 0.7112)
			(layers "B.Cu" "B.Mask" "B.Paste")
			(net "TP_BMC_GPION7")
		)
	)
	(footprint ""
		(layer "B.Cu")
		(at 82.919824 -145.101818 -90)
		(property "Reference" "R720"
			(at 0 0 90)
			(layer "B.SilkS")
			(hide yes)
			(effects
				(font
					(size 1.27 1.27)
				)
				(justify mirror)
			)
		)
		(property "Value" "0R2J-2-GP"
			(at -0.064008 -3.993896 270)
			(unlocked yes)
			(layer "B.Fab")
			(hide yes)
			(effects
				(font
					(size 1.016 1.016)
					(thickness 0.1524)
				)
				(justify mirror)
			)
		)
		(property "Device Type" "R402H16"
			(at -0.064008 -5.517896 270)
			(unlocked yes)
			(layer "B.Fab")
			(hide yes)
			(effects
				(font
					(size 1.016 1.016)
					(thickness 0.1524)
				)
				(justify mirror)
			)
		)
		(duplicate_pad_numbers_are_jumpers no)
		(fp_line
			(start -0.508 -0.9398)
			(end 0.508 -0.9398)
			(stroke
				(width 0.1524)
				(type default)
			)
			(layer "B.SilkS")
		)
		(fp_line
			(start 0.508 -0.9398)
			(end 0.508 0.9398)
			(stroke
				(width 0.1524)
				(type default)
			)
			(layer "B.SilkS")
		)
		(fp_rect
			(start 0.508 0.9398)
			(end -0.508 -0.9398)
			(stroke
				(width 0)
				(type default)
			)
			(fill no)
			(layer "B.CrtYd")
		)
		(fp_rect
			(start 0.508 0.9398)
			(end -0.508 -0.9398)
			(stroke
				(width 0)
				(type default)
			)
			(fill no)
			(layer "B.Fab")
		)
		(pad "1" smd custom
			(at 0 -0.4445 90)
			(size 0.1397 0.1397)
			(layers "B.Cu" "B.Mask" "B.Paste")
			(net "PWRGD_P3V3_STBY_N")
			(options
				(clearance outline)
				(anchor circle)
			)
			(primitives
				(gr_poly
					(pts
						(arc
							(start -0.1778 0.2794)
							(mid -0.249642 0.249642)
							(end -0.2794 0.1778)
						)
						(arc
							(start -0.2794 -0.1778)
							(mid -0.249642 -0.249642)
							(end -0.1778 -0.2794)
						)
						(arc
							(start 0.1778 -0.2794)
							(mid 0.249642 -0.249642)
							(end 0.2794 -0.1778)
						)
						(arc
							(start 0.2794 0.1778)
							(mid 0.249642 0.249642)
							(end 0.1778 0.2794)
						)
					)
					(width 0)
					(fill yes)
				)
			)
		)
		(pad "2" smd custom
			(at 0 0.4445 90)
			(size 0.1397 0.1397)
			(layers "B.Cu" "B.Mask" "B.Paste")
			(net "PWRGD_P3V3_STBY_N_R1")
			(options
				(clearance outline)
				(anchor circle)
			)
			(primitives
				(gr_poly
					(pts
						(arc
							(start -0.1778 0.2794)
							(mid -0.249642 0.249642)
							(end -0.2794 0.1778)
						)
						(arc
							(start -0.2794 -0.1778)
							(mid -0.249642 -0.249642)
							(end -0.1778 -0.2794)
						)
						(arc
							(start 0.1778 -0.2794)
							(mid 0.249642 -0.249642)
							(end 0.2794 -0.1778)
						)
						(arc
							(start 0.2794 0.1778)
							(mid 0.249642 0.249642)
							(end 0.1778 0.2794)
						)
					)
					(width 0)
					(fill yes)
				)
			)
		)
	)
)
